(kicad_pcb
	(version 20260206)
	(generator "pcbnew")
	(generator_version "10.0")
	(general
		(thickness 1.6)
		(legacy_teardrops no)
	)
	(paper "A4")
	(title_block
		(title "01162023_DA0F0TEBIF0_F0T_Expander_BD_F_brd_V02_OCP.brd")
		(comment 1 "Grand Teton / footprints 6760-6766 of 9728")
	)
	(layers
		(0 "F.Cu" signal "TOP")
		(4 "In1.Cu" signal "GND")
		(6 "In2.Cu" signal "VCC")
		(8 "In3.Cu" signal "VCC1")
		(10 "In4.Cu" signal "GND1")
		(12 "In5.Cu" signal "IN1")
		(14 "In6.Cu" signal "GND2")
		(16 "In7.Cu" signal "IN2")
		(18 "In8.Cu" signal "GND3")
		(20 "In9.Cu" signal "IN3")
		(22 "In10.Cu" signal "GND4")
		(24 "In11.Cu" signal "IN4")
		(26 "In12.Cu" signal "GND5")
		(28 "In13.Cu" signal "IN5")
		(30 "In14.Cu" signal "GND6")
		(32 "In15.Cu" signal "IN6")
		(34 "In16.Cu" signal "GND7")
		(2 "B.Cu" signal "BOTTOM")
		(9 "F.Adhes" user "F.Adhesive")
		(11 "B.Adhes" user "B.Adhesive")
		(13 "F.Paste" user "Package Geometry/Pastemask Top")
		(15 "B.Paste" user "Package Geometry/Pastemask Bottom")
		(5 "F.SilkS" user "Ref Des/Silkscreen Top")
		(7 "B.SilkS" user "Ref Des/Silkscreen Bottom")
		(1 "F.Mask" user "Board Geometry/Soldermask Top")
		(3 "B.Mask" user "Board Geometry/Soldermask Bottom")
		(17 "Dwgs.User" user "User.Drawings")
		(19 "Cmts.User" user "User.Comments")
		(21 "Eco1.User" user "User.Eco1")
		(23 "Eco2.User" user "User.Eco2")
		(25 "Edge.Cuts" user "Board Geometry/Outline")
		(27 "Margin" user)
		(31 "F.CrtYd" user "Package Geometry/Place Bound Top")
		(29 "B.CrtYd" user "Package Geometry/Place Bound Bottom")
		(35 "F.Fab" user "Ref Des/Assembly Top")
		(33 "B.Fab" user "Ref Des/Assembly Bottom")
	)
	(footprint ""
		(layer "F.Cu")
		(at 213.319868 -210.174586)
		(property "Reference" "R5523"
			(at 0 0 0)
			(layer "F.SilkS")
			(hide yes)
			(effects
				(font
					(size 1.27 1.27)
				)
			)
		)
		(property "Value" ""
			(at 0 0 0)
			(layer "F.Fab")
			(effects
				(font
					(size 1.27 1.27)
				)
			)
		)
		(duplicate_pad_numbers_are_jumpers no)
		(fp_line
			(start -0.7874 -0.4064)
			(end 0.7874 -0.4064)
			(stroke
				(width 0.1524)
				(type default)
			)
			(layer "F.SilkS")
		)
		(fp_line
			(start -0.7874 0.4064)
			(end -0.7874 -0.4064)
			(stroke
				(width 0.1524)
				(type default)
			)
			(layer "F.SilkS")
		)
		(fp_line
			(start 0.7874 -0.4064)
			(end 0.7874 0.4064)
			(stroke
				(width 0.1524)
				(type default)
			)
			(layer "F.SilkS")
		)
		(fp_line
			(start 0.7874 0.4064)
			(end -0.7874 0.4064)
			(stroke
				(width 0.1524)
				(type default)
			)
			(layer "F.SilkS")
		)
		(fp_line
			(start -0.67945 -0.305054)
			(end -0.12065 -0.305054)
			(stroke
				(width 0.1)
				(type default)
			)
			(layer "F.Fab")
		)
		(fp_line
			(start -0.67945 0.3048)
			(end -0.67945 -0.305054)
			(stroke
				(width 0.1)
				(type default)
			)
			(layer "F.Fab")
		)
		(fp_line
			(start -0.12065 -0.305054)
			(end -0.12065 -0.2794)
			(stroke
				(width 0.1)
				(type default)
			)
			(layer "F.Fab")
		)
		(fp_line
			(start -0.12065 -0.2794)
			(end 0.12065 -0.2794)
			(stroke
				(width 0.1)
				(type default)
			)
			(layer "F.Fab")
		)
		(fp_line
			(start -0.12065 0.2794)
			(end -0.12065 0.3048)
			(stroke
				(width 0.1)
				(type default)
			)
			(layer "F.Fab")
		)
		(fp_line
			(start -0.12065 0.3048)
			(end -0.67945 0.3048)
			(stroke
				(width 0.1)
				(type default)
			)
			(layer "F.Fab")
		)
		(fp_line
			(start 0.120396 0.2794)
			(end -0.12065 0.2794)
			(stroke
				(width 0.1)
				(type default)
			)
			(layer "F.Fab")
		)
		(fp_line
			(start 0.120396 0.3048)
			(end 0.120396 0.2794)
			(stroke
				(width 0.1)
				(type default)
			)
			(layer "F.Fab")
		)
		(fp_line
			(start 0.12065 -0.3048)
			(end 0.67945 -0.3048)
			(stroke
				(width 0.1)
				(type default)
			)
			(layer "F.Fab")
		)
		(fp_line
			(start 0.12065 -0.2794)
			(end 0.12065 -0.3048)
			(stroke
				(width 0.1)
				(type default)
			)
			(layer "F.Fab")
		)
		(fp_line
			(start 0.67945 -0.3048)
			(end 0.67945 0.3048)
			(stroke
				(width 0.1)
				(type default)
			)
			(layer "F.Fab")
		)
		(fp_line
			(start 0.67945 0.3048)
			(end 0.120396 0.3048)
			(stroke
				(width 0.1)
				(type default)
			)
			(layer "F.Fab")
		)
		(pad "1" smd circle
			(at -0.40005 0)
			(size 0 0)
			(layers "F.Cu" "F.Mask" "F.Paste")
			(net "P3V3_AUX")
		)
		(pad "2" smd circle
			(at 0.40005 0)
			(size 0 0)
			(layers "F.Cu" "F.Mask" "F.Paste")
			(net "RST_SSD_LED_IOEXP_R_N")
		)
	)
	(footprint ""
		(layer "F.Cu")
		(at 131.370578 -190.358522 180)
		(property "Reference" "R6675"
			(at 0 0 180)
			(layer "F.SilkS")
			(hide yes)
			(effects
				(font
					(size 1.27 1.27)
				)
			)
		)
		(property "Value" ""
			(at 0 0 180)
			(layer "F.Fab")
			(effects
				(font
					(size 1.27 1.27)
				)
			)
		)
		(duplicate_pad_numbers_are_jumpers no)
		(fp_line
			(start 0.7874 0.4064)
			(end -0.7874 0.4064)
			(stroke
				(width 0.1524)
				(type default)
			)
			(layer "F.SilkS")
		)
		(fp_line
			(start 0.7874 -0.4064)
			(end 0.7874 0.4064)
			(stroke
				(width 0.1524)
				(type default)
			)
			(layer "F.SilkS")
		)
		(fp_line
			(start -0.7874 0.4064)
			(end -0.7874 -0.4064)
			(stroke
				(width 0.1524)
				(type default)
			)
			(layer "F.SilkS")
		)
		(fp_line
			(start -0.7874 -0.4064)
			(end 0.7874 -0.4064)
			(stroke
				(width 0.1524)
				(type default)
			)
			(layer "F.SilkS")
		)
		(fp_line
			(start 0.67945 0.3048)
			(end 0.120396 0.3048)
			(stroke
				(width 0.1)
				(type default)
			)
			(layer "F.Fab")
		)
		(fp_line
			(start 0.67945 -0.3048)
			(end 0.67945 0.3048)
			(stroke
				(width 0.1)
				(type default)
			)
			(layer "F.Fab")
		)
		(fp_line
			(start 0.12065 -0.2794)
			(end 0.12065 -0.3048)
			(stroke
				(width 0.1)
				(type default)
			)
			(layer "F.Fab")
		)
		(fp_line
			(start 0.12065 -0.3048)
			(end 0.67945 -0.3048)
			(stroke
				(width 0.1)
				(type default)
			)
			(layer "F.Fab")
		)
		(fp_line
			(start 0.120396 0.3048)
			(end 0.120396 0.2794)
			(stroke
				(width 0.1)
				(type default)
			)
			(layer "F.Fab")
		)
		(fp_line
			(start 0.120396 0.2794)
			(end -0.12065 0.2794)
			(stroke
				(width 0.1)
				(type default)
			)
			(layer "F.Fab")
		)
		(fp_line
			(start -0.12065 0.3048)
			(end -0.67945 0.3048)
			(stroke
				(width 0.1)
				(type default)
			)
			(layer "F.Fab")
		)
		(fp_line
			(start -0.12065 0.2794)
			(end -0.12065 0.3048)
			(stroke
				(width 0.1)
				(type default)
			)
			(layer "F.Fab")
		)
		(fp_line
			(start -0.12065 -0.2794)
			(end 0.12065 -0.2794)
			(stroke
				(width 0.1)
				(type default)
			)
			(layer "F.Fab")
		)
		(fp_line
			(start -0.12065 -0.305054)
			(end -0.12065 -0.2794)
			(stroke
				(width 0.1)
				(type default)
			)
			(layer "F.Fab")
		)
		(fp_line
			(start -0.67945 0.3048)
			(end -0.67945 -0.305054)
			(stroke
				(width 0.1)
				(type default)
			)
			(layer "F.Fab")
		)
		(fp_line
			(start -0.67945 -0.305054)
			(end -0.12065 -0.305054)
			(stroke
				(width 0.1)
				(type default)
			)
			(layer "F.Fab")
		)
		(pad "1" smd circle
			(at -0.40005 0 180)
			(size 0 0)
			(layers "F.Cu" "F.Mask" "F.Paste")
			(net "NIC6_CLK_EN_BUF_R_N")
		)
		(pad "2" smd circle
			(at 0.40005 0 180)
			(size 0 0)
			(layers "F.Cu" "F.Mask" "F.Paste")
			(net "P3V3")
		)
	)
	(footprint ""
		(layer "F.Cu")
		(at 275.004022 -356.244906 90)
		(property "Reference" "C2348"
			(at 0 0 90)
			(layer "F.SilkS")
			(hide yes)
			(effects
				(font
					(size 1.27 1.27)
				)
			)
		)
		(property "Value" ""
			(at 0 0 90)
			(layer "F.Fab")
			(effects
				(font
					(size 1.27 1.27)
				)
			)
		)
		(duplicate_pad_numbers_are_jumpers no)
		(fp_line
			(start 0.299974 -0.150114)
			(end 0.299974 0.150114)
			(stroke
				(width 0.1)
				(type default)
			)
			(layer "F.Fab")
		)
		(fp_line
			(start -0.299974 -0.150114)
			(end 0.299974 -0.150114)
			(stroke
				(width 0.1)
				(type default)
			)
			(layer "F.Fab")
		)
		(fp_line
			(start 0.299974 0.150114)
			(end -0.299974 0.150114)
			(stroke
				(width 0.1)
				(type default)
			)
			(layer "F.Fab")
		)
		(fp_line
			(start -0.299974 0.150114)
			(end -0.299974 -0.150114)
			(stroke
				(width 0.1)
				(type default)
			)
			(layer "F.Fab")
		)
		(pad "1" smd rect
			(at -0.2667 0 90)
			(size 0.3048 0.381)
			(layers "F.Cu" "F.Mask" "F.Paste")
			(net "P5E_PEX2_STN4_TX_DN<76>")
		)
		(pad "2" smd rect
			(at 0.2667 0 90)
			(size 0.3048 0.381)
			(layers "F.Cu" "F.Mask" "F.Paste")
			(net "P5E_PEX2_STN4_TX_C_DN<76>")
		)
	)
	(footprint ""
		(layer "F.Cu")
		(at 387.580632 -125.519942)
		(property "Reference" "C675"
			(at 0 0 0)
			(layer "F.SilkS")
			(hide yes)
			(effects
				(font
					(size 1.27 1.27)
				)
			)
		)
		(property "Value" ""
			(at 0 0 0)
			(layer "F.Fab")
			(effects
				(font
					(size 1.27 1.27)
				)
			)
		)
		(duplicate_pad_numbers_are_jumpers no)
		(fp_line
			(start -0.299974 -0.150114)
			(end 0.299974 -0.150114)
			(stroke
				(width 0.1)
				(type default)
			)
			(layer "F.Fab")
		)
		(fp_line
			(start -0.299974 0.150114)
			(end -0.299974 -0.150114)
			(stroke
				(width 0.1)
				(type default)
			)
			(layer "F.Fab")
		)
		(fp_line
			(start 0.299974 -0.150114)
			(end 0.299974 0.150114)
			(stroke
				(width 0.1)
				(type default)
			)
			(layer "F.Fab")
		)
		(fp_line
			(start 0.299974 0.150114)
			(end -0.299974 0.150114)
			(stroke
				(width 0.1)
				(type default)
			)
			(layer "F.Fab")
		)
		(pad "1" smd rect
			(at -0.2667 0)
			(size 0.3048 0.381)
			(layers "F.Cu" "F.Mask" "F.Paste")
			(net "P5E_PEX3_STN1_TX_DP<27>")
		)
		(pad "2" smd rect
			(at 0.2667 0)
			(size 0.3048 0.381)
			(layers "F.Cu" "F.Mask" "F.Paste")
			(net "P5E_PEX3_STN1_TX_C_DP<27>")
		)
	)
	(footprint ""
		(layer "F.Cu")
		(at 288.181542 -157.8356)
		(property "Reference" "R252"
			(at 0 0 0)
			(layer "F.SilkS")
			(hide yes)
			(effects
				(font
					(size 1.27 1.27)
				)
			)
		)
		(property "Value" ""
			(at 0 0 0)
			(layer "F.Fab")
			(effects
				(font
					(size 1.27 1.27)
				)
			)
		)
		(duplicate_pad_numbers_are_jumpers no)
		(fp_line
			(start -0.7874 -0.4064)
			(end 0.7874 -0.4064)
			(stroke
				(width 0.1524)
				(type default)
			)
			(layer "F.SilkS")
		)
		(fp_line
			(start -0.7874 0.4064)
			(end -0.7874 -0.4064)
			(stroke
				(width 0.1524)
				(type default)
			)
			(layer "F.SilkS")
		)
		(fp_line
			(start 0.7874 -0.4064)
			(end 0.7874 0.4064)
			(stroke
				(width 0.1524)
				(type default)
			)
			(layer "F.SilkS")
		)
		(fp_line
			(start 0.7874 0.4064)
			(end -0.7874 0.4064)
			(stroke
				(width 0.1524)
				(type default)
			)
			(layer "F.SilkS")
		)
		(fp_line
			(start -0.67945 -0.305054)
			(end -0.12065 -0.305054)
			(stroke
				(width 0.1)
				(type default)
			)
			(layer "F.Fab")
		)
		(fp_line
			(start -0.67945 0.3048)
			(end -0.67945 -0.305054)
			(stroke
				(width 0.1)
				(type default)
			)
			(layer "F.Fab")
		)
		(fp_line
			(start -0.12065 -0.305054)
			(end -0.12065 -0.2794)
			(stroke
				(width 0.1)
				(type default)
			)
			(layer "F.Fab")
		)
		(fp_line
			(start -0.12065 -0.2794)
			(end 0.12065 -0.2794)
			(stroke
				(width 0.1)
				(type default)
			)
			(layer "F.Fab")
		)
		(fp_line
			(start -0.12065 0.2794)
			(end -0.12065 0.3048)
			(stroke
				(width 0.1)
				(type default)
			)
			(layer "F.Fab")
		)
		(fp_line
			(start -0.12065 0.3048)
			(end -0.67945 0.3048)
			(stroke
				(width 0.1)
				(type default)
			)
			(layer "F.Fab")
		)
		(fp_line
			(start 0.120396 0.2794)
			(end -0.12065 0.2794)
			(stroke
				(width 0.1)
				(type default)
			)
			(layer "F.Fab")
		)
		(fp_line
			(start 0.120396 0.3048)
			(end 0.120396 0.2794)
			(stroke
				(width 0.1)
				(type default)
			)
			(layer "F.Fab")
		)
		(fp_line
			(start 0.12065 -0.3048)
			(end 0.67945 -0.3048)
			(stroke
				(width 0.1)
				(type default)
			)
			(layer "F.Fab")
		)
		(fp_line
			(start 0.12065 -0.2794)
			(end 0.12065 -0.3048)
			(stroke
				(width 0.1)
				(type default)
			)
			(layer "F.Fab")
		)
		(fp_line
			(start 0.67945 -0.3048)
			(end 0.67945 0.3048)
			(stroke
				(width 0.1)
				(type default)
			)
			(layer "F.Fab")
		)
		(fp_line
			(start 0.67945 0.3048)
			(end 0.120396 0.3048)
			(stroke
				(width 0.1)
				(type default)
			)
			(layer "F.Fab")
		)
		(pad "1" smd circle
			(at -0.40005 0)
			(size 0 0)
			(layers "F.Cu" "F.Mask" "F.Paste")
			(net "RST_NIC4_PERST3_R_N")
		)
		(pad "2" smd circle
			(at 0.40005 0)
			(size 0 0)
			(layers "F.Cu" "F.Mask" "F.Paste")
			(net "RST_HP_NIC4_BUF_N")
		)
	)
	(footprint ""
		(layer "F.Cu")
		(at 166.330884 -196.884798)
		(property "Reference" "R3403"
			(at 0 0 0)
			(layer "F.SilkS")
			(hide yes)
			(effects
				(font
					(size 1.27 1.27)
				)
			)
		)
		(property "Value" ""
			(at 0 0 0)
			(layer "F.Fab")
			(effects
				(font
					(size 1.27 1.27)
				)
			)
		)
		(duplicate_pad_numbers_are_jumpers no)
		(fp_line
			(start -0.7874 -0.4064)
			(end 0.7874 -0.4064)
			(stroke
				(width 0.1524)
				(type default)
			)
			(layer "F.SilkS")
		)
		(fp_line
			(start -0.7874 0.4064)
			(end -0.7874 -0.4064)
			(stroke
				(width 0.1524)
				(type default)
			)
			(layer "F.SilkS")
		)
		(fp_line
			(start 0.7874 -0.4064)
			(end 0.7874 0.4064)
			(stroke
				(width 0.1524)
				(type default)
			)
			(layer "F.SilkS")
		)
		(fp_line
			(start 0.7874 0.4064)
			(end -0.7874 0.4064)
			(stroke
				(width 0.1524)
				(type default)
			)
			(layer "F.SilkS")
		)
		(fp_line
			(start -0.67945 -0.305054)
			(end -0.12065 -0.305054)
			(stroke
				(width 0.1)
				(type default)
			)
			(layer "F.Fab")
		)
		(fp_line
			(start -0.67945 0.3048)
			(end -0.67945 -0.305054)
			(stroke
				(width 0.1)
				(type default)
			)
			(layer "F.Fab")
		)
		(fp_line
			(start -0.12065 -0.305054)
			(end -0.12065 -0.2794)
			(stroke
				(width 0.1)
				(type default)
			)
			(layer "F.Fab")
		)
		(fp_line
			(start -0.12065 -0.2794)
			(end 0.12065 -0.2794)
			(stroke
				(width 0.1)
				(type default)
			)
			(layer "F.Fab")
		)
		(fp_line
			(start -0.12065 0.2794)
			(end -0.12065 0.3048)
			(stroke
				(width 0.1)
				(type default)
			)
			(layer "F.Fab")
		)
		(fp_line
			(start -0.12065 0.3048)
			(end -0.67945 0.3048)
			(stroke
				(width 0.1)
				(type default)
			)
			(layer "F.Fab")
		)
		(fp_line
			(start 0.120396 0.2794)
			(end -0.12065 0.2794)
			(stroke
				(width 0.1)
				(type default)
			)
			(layer "F.Fab")
		)
		(fp_line
			(start 0.120396 0.3048)
			(end 0.120396 0.2794)
			(stroke
				(width 0.1)
				(type default)
			)
			(layer "F.Fab")
		)
		(fp_line
			(start 0.12065 -0.3048)
			(end 0.67945 -0.3048)
			(stroke
				(width 0.1)
				(type default)
			)
			(layer "F.Fab")
		)
		(fp_line
			(start 0.12065 -0.2794)
			(end 0.12065 -0.3048)
			(stroke
				(width 0.1)
				(type default)
			)
			(layer "F.Fab")
		)
		(fp_line
			(start 0.67945 -0.3048)
			(end 0.67945 0.3048)
			(stroke
				(width 0.1)
				(type default)
			)
			(layer "F.Fab")
		)
		(fp_line
			(start 0.67945 0.3048)
			(end 0.120396 0.3048)
			(stroke
				(width 0.1)
				(type default)
			)
			(layer "F.Fab")
		)
		(pad "1" smd circle
			(at -0.40005 0)
			(size 0 0)
			(layers "F.Cu" "F.Mask" "F.Paste")
			(net "SPI_BIC1_CLK_LS01_R1")
		)
		(pad "2" smd circle
			(at 0.40005 0)
			(size 0 0)
			(layers "F.Cu" "F.Mask" "F.Paste")
			(net "SPI_BIC1_CLK_LS01_R")
		)
	)
	(footprint ""
		(layer "F.Cu")
		(at 337.221322 -303.698402 90)
		(property "Reference" "PC169"
			(at 0 0 90)
			(layer "F.SilkS")
			(hide yes)
			(effects
				(font
					(size 1.27 1.27)
				)
			)
		)
		(property "Value" ""
			(at 0 0 90)
			(layer "F.Fab")
			(effects
				(font
					(size 1.27 1.27)
				)
			)
		)
		(duplicate_pad_numbers_are_jumpers no)
		(fp_line
			(start -4.53898 -2.150618)
			(end -4.539742 2.152142)
			(stroke
				(width 0.1524)
				(type default)
			)
			(layer "F.SilkS")
		)
		(fp_line
			(start -4.69138 -2.150618)
			(end -4.692396 2.161032)
			(stroke
				(width 0.1524)
				(type default)
			)
			(layer "F.SilkS")
		)
		(fp_line
			(start -4.84378 -2.150618)
			(end -4.53898 -2.150618)
			(stroke
				(width 0.1524)
				(type default)
			)
			(layer "F.SilkS")
		)
		(fp_line
			(start -4.84378 -2.150618)
			(end -4.842256 2.163064)
			(stroke
				(width 0.1524)
				(type default)
			)
			(layer "F.SilkS")
		)
		(fp_line
			(start 4.53898 -2.15011)
			(end 4.53898 2.15011)
			(stroke
				(width 0.1524)
				(type default)
			)
			(layer "F.SilkS")
		)
		(fp_line
			(start -4.53898 -2.15011)
			(end 4.53898 -2.15011)
			(stroke
				(width 0.1524)
				(type default)
			)
			(layer "F.SilkS")
		)
		(fp_line
			(start 4.53898 2.15011)
			(end -4.53898 2.15011)
			(stroke
				(width 0.1524)
				(type default)
			)
			(layer "F.SilkS")
		)
		(fp_line
			(start -4.53898 2.15011)
			(end -4.53898 -2.15011)
			(stroke
				(width 0.1524)
				(type default)
			)
			(layer "F.SilkS")
		)
		(fp_line
			(start -4.83108 2.150364)
			(end -4.447794 2.149348)
			(stroke
				(width 0.1524)
				(type default)
			)
			(layer "F.SilkS")
		)
		(fp_line
			(start 3.64998 -2.15011)
			(end 3.64998 2.15011)
			(stroke
				(width 0.1)
				(type default)
			)
			(layer "F.Fab")
		)
		(fp_line
			(start -3.64998 -2.15011)
			(end 3.64998 -2.15011)
			(stroke
				(width 0.1)
				(type default)
			)
			(layer "F.Fab")
		)
		(fp_line
			(start 3.64998 2.15011)
			(end -3.64998 2.15011)
			(stroke
				(width 0.1)
				(type default)
			)
			(layer "F.Fab")
		)
		(fp_line
			(start -3.64998 2.15011)
			(end -3.64998 -2.15011)
			(stroke
				(width 0.1)
				(type default)
			)
			(layer "F.Fab")
		)
		(fp_text user "-"
			(at 4.729226 -0.216662 90)
			(unlocked yes)
			(layer "F.SilkS")
			(effects
				(font
					(size 1.905 1.4224)
					(thickness 0.1524)
				)
				(justify left)
			)
		)
		(fp_text user "+"
			(at -5.031486 2.604262 90)
			(unlocked yes)
			(layer "F.SilkS")
			(effects
				(font
					(size 1.905 1.4224)
					(thickness 0.1524)
				)
				(justify left)
			)
		)
		(fp_text user "+"
			(at -6.214872 -0.337058 90)
			(unlocked yes)
			(layer "F.Fab")
			(effects
				(font
					(size 1.905 1.4224)
					(thickness 0.1524)
				)
				(justify left)
			)
		)
		(fp_text user "-"
			(at 4.313174 -0.094488 90)
			(unlocked yes)
			(layer "F.Fab")
			(effects
				(font
					(size 1.905 1.4224)
					(thickness 0.1524)
				)
				(justify left)
			)
		)
		(pad "1" smd rect
			(at -3.199892 0 90)
			(size 2.413 2.8194)
			(layers "F.Cu" "F.Mask" "F.Paste")
			(net "P0V8_PEX2")
		)
		(pad "2" smd rect
			(at 3.199892 0 90)
			(size 2.413 2.8194)
			(layers "F.Cu" "F.Mask" "F.Paste")
			(net "GND")
		)
	)
)
